# S9S_MB_2U (Grand Teton) — schematic netlist excerpt (pin names and nets, part order shuffled) for the footprints in the layout excerpt that follows; sources: Cadence DE-HDL packaged netlist, KiCad conversion of 03242023_DA0F0TMBIJ0_F0T_Motherboard_J_brd_V01_OCP.brd

C2377  Q_CAP  0.1UF 25V 10% X7R  pkg 0402  page 164 : A = P3V3_AUX ; B = GND
R3025  Q_RES  1K 1% EMPTY  pkg 0402LF  page 134 : A = FM_REMOTE_DEBUG_DET_R ; B = GND

(kicad_pcb
	(version 20260206)
	(generator "pcbnew")
	(generator_version "10.0")
	(general
		(thickness 1.6)
		(legacy_teardrops no)
	)
	(paper "A4")
	(title_block
		(title "03242023_DA0F0TMBIJ0_F0T_Motherboard_J_brd_V01_OCP.brd")
		(comment 1 "Grand Teton / footprints 3526-3527 of 6105")
	)
	(layers
		(0 "F.Cu" signal "TOP")
		(4 "In1.Cu" signal "GND")
		(6 "In2.Cu" signal "IN1")
		(8 "In3.Cu" signal "GND1")
		(10 "In4.Cu" signal "IN2")
		(12 "In5.Cu" signal "GND2")
		(14 "In6.Cu" signal "IN3")
		(16 "In7.Cu" signal "GND3")
		(18 "In8.Cu" signal "VCC")
		(20 "In9.Cu" signal "VCC1")
		(22 "In10.Cu" signal "GND4")
		(24 "In11.Cu" signal "IN4")
		(26 "In12.Cu" signal "GND5")
		(28 "In13.Cu" signal "IN5")
		(30 "In14.Cu" signal "GND6")
		(32 "In15.Cu" signal "IN6")
		(34 "In16.Cu" signal "GND7")
		(2 "B.Cu" signal "BOTTOM")
		(9 "F.Adhes" user "F.Adhesive")
		(11 "B.Adhes" user "B.Adhesive")
		(13 "F.Paste" user "Package Geometry/Pastemask Top")
		(15 "B.Paste" user "Package Geometry/Pastemask Bottom")
		(5 "F.SilkS" user "Ref Des/Silkscreen Top")
		(7 "B.SilkS" user "Ref Des/Silkscreen Bottom")
		(1 "F.Mask" user "Board Geometry/Soldermask Top")
		(3 "B.Mask" user "Board Geometry/Soldermask Bottom")
		(17 "Dwgs.User" user "User.Drawings")
		(19 "Cmts.User" user "User.Comments")
		(21 "Eco1.User" user "User.Eco1")
		(23 "Eco2.User" user "User.Eco2")
		(25 "Edge.Cuts" user "Board Geometry/Outline")
		(27 "Margin" user)
		(31 "F.CrtYd" user "Package Geometry/Place Bound Top")
		(29 "B.CrtYd" user "Package Geometry/Place Bound Bottom")
		(35 "F.Fab" user "Ref Des/Assembly Top")
		(33 "B.Fab" user "Ref Des/Assembly Bottom")
	)
	(footprint ""
		(layer "F.Cu")
		(at 143.895318 -114.73434)
		(property "Reference" "C2377"
			(at 0 0 0)
			(layer "F.SilkS")
			(hide yes)
			(effects
				(font
					(size 1.27 1.27)
				)
			)
		)
		(property "Value" ""
			(at 0 0 0)
			(layer "F.Fab")
			(effects
				(font
					(size 1.27 1.27)
				)
			)
		)
		(duplicate_pad_numbers_are_jumpers no)
		(fp_line
			(start -0.7874 -0.4064)
			(end 0.7874 -0.4064)
			(stroke
				(width 0.1524)
				(type default)
			)
			(layer "F.SilkS")
		)
		(fp_line
			(start -0.7874 0.4064)
			(end -0.7874 -0.4064)
			(stroke
				(width 0.1524)
				(type default)
			)
			(layer "F.SilkS")
		)
		(fp_line
			(start 0.7874 -0.4064)
			(end 0.7874 0.4064)
			(stroke
				(width 0.1524)
				(type default)
			)
			(layer "F.SilkS")
		)
		(fp_line
			(start 0.7874 0.4064)
			(end -0.7874 0.4064)
			(stroke
				(width 0.1524)
				(type default)
			)
			(layer "F.SilkS")
		)
		(fp_line
			(start -0.67945 -0.305054)
			(end -0.12065 -0.305054)
			(stroke
				(width 0.1)
				(type default)
			)
			(layer "F.Fab")
		)
		(fp_line
			(start -0.67945 0.3048)
			(end -0.67945 -0.305054)
			(stroke
				(width 0.1)
				(type default)
			)
			(layer "F.Fab")
		)
		(fp_line
			(start -0.12065 -0.305054)
			(end -0.12065 -0.2794)
			(stroke
				(width 0.1)
				(type default)
			)
			(layer "F.Fab")
		)
		(fp_line
			(start -0.12065 -0.2794)
			(end 0.12065 -0.2794)
			(stroke
				(width 0.1)
				(type default)
			)
			(layer "F.Fab")
		)
		(fp_line
			(start -0.12065 0.2794)
			(end -0.12065 0.3048)
			(stroke
				(width 0.1)
				(type default)
			)
			(layer "F.Fab")
		)
		(fp_line
			(start -0.12065 0.3048)
			(end -0.67945 0.3048)
			(stroke
				(width 0.1)
				(type default)
			)
			(layer "F.Fab")
		)
		(fp_line
			(start 0.120396 0.2794)
			(end -0.12065 0.2794)
			(stroke
				(width 0.1)
				(type default)
			)
			(layer "F.Fab")
		)
		(fp_line
			(start 0.120396 0.3048)
			(end 0.120396 0.2794)
			(stroke
				(width 0.1)
				(type default)
			)
			(layer "F.Fab")
		)
		(fp_line
			(start 0.12065 -0.3048)
			(end 0.67945 -0.3048)
			(stroke
				(width 0.1)
				(type default)
			)
			(layer "F.Fab")
		)
		(fp_line
			(start 0.12065 -0.2794)
			(end 0.12065 -0.3048)
			(stroke
				(width 0.1)
				(type default)
			)
			(layer "F.Fab")
		)
		(fp_line
			(start 0.67945 -0.3048)
			(end 0.67945 0.3048)
			(stroke
				(width 0.1)
				(type default)
			)
			(layer "F.Fab")
		)
		(fp_line
			(start 0.67945 0.3048)
			(end 0.120396 0.3048)
			(stroke
				(width 0.1)
				(type default)
			)
			(layer "F.Fab")
		)
		(pad "1" smd circle
			(at -0.40005 0)
			(size 0 0)
			(layers "F.Cu" "F.Mask" "F.Paste")
			(net "P3V3_AUX")
		)
		(pad "2" smd circle
			(at 0.40005 0)
			(size 0 0)
			(layers "F.Cu" "F.Mask" "F.Paste")
			(net "GND")
		)
	)
	(footprint ""
		(layer "F.Cu")
		(at 90.09888 -57.368948 180)
		(property "Reference" "R3025"
			(at 0 0 180)
			(layer "F.SilkS")
			(hide yes)
			(effects
				(font
					(size 1.27 1.27)
				)
			)
		)
		(property "Value" ""
			(at 0 0 180)
			(layer "F.Fab")
			(effects
				(font
					(size 1.27 1.27)
				)
			)
		)
		(duplicate_pad_numbers_are_jumpers no)
		(fp_line
			(start 0.7874 0.4064)
			(end -0.7874 0.4064)
			(stroke
				(width 0.1524)
				(type default)
			)
			(layer "F.SilkS")
		)
		(fp_line
			(start 0.7874 -0.4064)
			(end 0.7874 0.4064)
			(stroke
				(width 0.1524)
				(type default)
			)
			(layer "F.SilkS")
		)
		(fp_line
			(start -0.7874 0.4064)
			(end -0.7874 -0.4064)
			(stroke
				(width 0.1524)
				(type default)
			)
			(layer "F.SilkS")
		)
		(fp_line
			(start -0.7874 -0.4064)
			(end 0.7874 -0.4064)
			(stroke
				(width 0.1524)
				(type default)
			)
			(layer "F.SilkS")
		)
		(fp_line
			(start 0.67945 0.3048)
			(end 0.120396 0.3048)
			(stroke
				(width 0.1)
				(type default)
			)
			(layer "F.Fab")
		)
		(fp_line
			(start 0.67945 -0.3048)
			(end 0.67945 0.3048)
			(stroke
				(width 0.1)
				(type default)
			)
			(layer "F.Fab")
		)
		(fp_line
			(start 0.12065 -0.2794)
			(end 0.12065 -0.3048)
			(stroke
				(width 0.1)
				(type default)
			)
			(layer "F.Fab")
		)
		(fp_line
			(start 0.12065 -0.3048)
			(end 0.67945 -0.3048)
			(stroke
				(width 0.1)
				(type default)
			)
			(layer "F.Fab")
		)
		(fp_line
			(start 0.120396 0.3048)
			(end 0.120396 0.2794)
			(stroke
				(width 0.1)
				(type default)
			)
			(layer "F.Fab")
		)
		(fp_line
			(start 0.120396 0.2794)
			(end -0.12065 0.2794)
			(stroke
				(width 0.1)
				(type default)
			)
			(layer "F.Fab")
		)
		(fp_line
			(start -0.12065 0.3048)
			(end -0.67945 0.3048)
			(stroke
				(width 0.1)
				(type default)
			)
			(layer "F.Fab")
		)
		(fp_line
			(start -0.12065 0.2794)
			(end -0.12065 0.3048)
			(stroke
				(width 0.1)
				(type default)
			)
			(layer "F.Fab")
		)
		(fp_line
			(start -0.12065 -0.2794)
			(end 0.12065 -0.2794)
			(stroke
				(width 0.1)
				(type default)
			)
			(layer "F.Fab")
		)
		(fp_line
			(start -0.12065 -0.305054)
			(end -0.12065 -0.2794)
			(stroke
				(width 0.1)
				(type default)
			)
			(layer "F.Fab")
		)
		(fp_line
			(start -0.67945 0.3048)
			(end -0.67945 -0.305054)
			(stroke
				(width 0.1)
				(type default)
			)
			(layer "F.Fab")
		)
		(fp_line
			(start -0.67945 -0.305054)
			(end -0.12065 -0.305054)
			(stroke
				(width 0.1)
				(type default)
			)
			(layer "F.Fab")
		)
		(pad "1" smd circle
			(at -0.40005 0 180)
			(size 0 0)
			(layers "F.Cu" "F.Mask" "F.Paste")
			(net "FM_REMOTE_DEBUG_DET_R")
		)
		(pad "2" smd circle
			(at 0.40005 0 180)
			(size 0 0)
			(layers "F.Cu" "F.Mask" "F.Paste")
			(net "GND")
		)
	)
)
